# S9S_MB_2U (Grand Teton) — schematic netlist excerpt (pin names and nets, part order shuffled) for the footprints in the layout excerpt that follows; sources: Cadence DE-HDL packaged netlist, KiCad conversion of 03242023_DA0F0TMBIJ0_F0T_Motherboard_J_brd_V01_OCP.brd

R4453  Q_RES  47K 0.1% EMPTY  pkg 0402LF  page 196 : A = GND ; B = RST_USB_HUB_2_R_N
C1025  Q_CAP  22UF 4V 20% X6S  pkg C0402  page 74 : A = PVCCIN_CPU0 ; B = GND

(kicad_pcb
	(version 20260206)
	(generator "pcbnew")
	(generator_version "10.0")
	(general
		(thickness 1.6)
		(legacy_teardrops no)
	)
	(paper "A4")
	(title_block
		(title "03242023_DA0F0TMBIJ0_F0T_Motherboard_J_brd_V01_OCP.brd")
		(comment 1 "Grand Teton / footprints 3569-3570 of 6105")
	)
	(layers
		(0 "F.Cu" signal "TOP")
		(4 "In1.Cu" signal "GND")
		(6 "In2.Cu" signal "IN1")
		(8 "In3.Cu" signal "GND1")
		(10 "In4.Cu" signal "IN2")
		(12 "In5.Cu" signal "GND2")
		(14 "In6.Cu" signal "IN3")
		(16 "In7.Cu" signal "GND3")
		(18 "In8.Cu" signal "VCC")
		(20 "In9.Cu" signal "VCC1")
		(22 "In10.Cu" signal "GND4")
		(24 "In11.Cu" signal "IN4")
		(26 "In12.Cu" signal "GND5")
		(28 "In13.Cu" signal "IN5")
		(30 "In14.Cu" signal "GND6")
		(32 "In15.Cu" signal "IN6")
		(34 "In16.Cu" signal "GND7")
		(2 "B.Cu" signal "BOTTOM")
		(9 "F.Adhes" user "F.Adhesive")
		(11 "B.Adhes" user "B.Adhesive")
		(13 "F.Paste" user "Package Geometry/Pastemask Top")
		(15 "B.Paste" user "Package Geometry/Pastemask Bottom")
		(5 "F.SilkS" user "Ref Des/Silkscreen Top")
		(7 "B.SilkS" user "Ref Des/Silkscreen Bottom")
		(1 "F.Mask" user "Board Geometry/Soldermask Top")
		(3 "B.Mask" user "Board Geometry/Soldermask Bottom")
		(17 "Dwgs.User" user "User.Drawings")
		(19 "Cmts.User" user "User.Comments")
		(21 "Eco1.User" user "User.Eco1")
		(23 "Eco2.User" user "User.Eco2")
		(25 "Edge.Cuts" user "Board Geometry/Outline")
		(27 "Margin" user)
		(31 "F.CrtYd" user "Package Geometry/Place Bound Top")
		(29 "B.CrtYd" user "Package Geometry/Place Bound Bottom")
		(35 "F.Fab" user "Ref Des/Assembly Top")
		(33 "B.Fab" user "Ref Des/Assembly Bottom")
	)
	(footprint ""
		(layer "F.Cu")
		(at 154.966416 -31.341568 90)
		(property "Reference" "R4453"
			(at 0 0 90)
			(layer "F.SilkS")
			(hide yes)
			(effects
				(font
					(size 1.27 1.27)
				)
			)
		)
		(property "Value" ""
			(at 0 0 90)
			(layer "F.Fab")
			(effects
				(font
					(size 1.27 1.27)
				)
			)
		)
		(duplicate_pad_numbers_are_jumpers no)
		(fp_line
			(start 0.7874 -0.4064)
			(end 0.7874 0.4064)
			(stroke
				(width 0.1524)
				(type default)
			)
			(layer "F.SilkS")
		)
		(fp_line
			(start -0.7874 -0.4064)
			(end 0.7874 -0.4064)
			(stroke
				(width 0.1524)
				(type default)
			)
			(layer "F.SilkS")
		)
		(fp_line
			(start 0.7874 0.4064)
			(end -0.7874 0.4064)
			(stroke
				(width 0.1524)
				(type default)
			)
			(layer "F.SilkS")
		)
		(fp_line
			(start -0.7874 0.4064)
			(end -0.7874 -0.4064)
			(stroke
				(width 0.1524)
				(type default)
			)
			(layer "F.SilkS")
		)
		(fp_line
			(start -0.12065 -0.305054)
			(end -0.12065 -0.2794)
			(stroke
				(width 0.1)
				(type default)
			)
			(layer "F.Fab")
		)
		(fp_line
			(start -0.67945 -0.305054)
			(end -0.12065 -0.305054)
			(stroke
				(width 0.1)
				(type default)
			)
			(layer "F.Fab")
		)
		(fp_line
			(start 0.67945 -0.3048)
			(end 0.67945 0.3048)
			(stroke
				(width 0.1)
				(type default)
			)
			(layer "F.Fab")
		)
		(fp_line
			(start 0.12065 -0.3048)
			(end 0.67945 -0.3048)
			(stroke
				(width 0.1)
				(type default)
			)
			(layer "F.Fab")
		)
		(fp_line
			(start 0.12065 -0.2794)
			(end 0.12065 -0.3048)
			(stroke
				(width 0.1)
				(type default)
			)
			(layer "F.Fab")
		)
		(fp_line
			(start -0.12065 -0.2794)
			(end 0.12065 -0.2794)
			(stroke
				(width 0.1)
				(type default)
			)
			(layer "F.Fab")
		)
		(fp_line
			(start 0.120396 0.2794)
			(end -0.12065 0.2794)
			(stroke
				(width 0.1)
				(type default)
			)
			(layer "F.Fab")
		)
		(fp_line
			(start -0.12065 0.2794)
			(end -0.12065 0.3048)
			(stroke
				(width 0.1)
				(type default)
			)
			(layer "F.Fab")
		)
		(fp_line
			(start 0.67945 0.3048)
			(end 0.120396 0.3048)
			(stroke
				(width 0.1)
				(type default)
			)
			(layer "F.Fab")
		)
		(fp_line
			(start 0.120396 0.3048)
			(end 0.120396 0.2794)
			(stroke
				(width 0.1)
				(type default)
			)
			(layer "F.Fab")
		)
		(fp_line
			(start -0.12065 0.3048)
			(end -0.67945 0.3048)
			(stroke
				(width 0.1)
				(type default)
			)
			(layer "F.Fab")
		)
		(fp_line
			(start -0.67945 0.3048)
			(end -0.67945 -0.305054)
			(stroke
				(width 0.1)
				(type default)
			)
			(layer "F.Fab")
		)
		(pad "1" smd circle
			(at -0.40005 0 90)
			(size 0 0)
			(layers "F.Cu" "F.Mask" "F.Paste")
			(net "GND")
		)
		(pad "2" smd circle
			(at 0.40005 0 90)
			(size 0 0)
			(layers "F.Cu" "F.Mask" "F.Paste")
			(net "RST_USB_HUB_2_R_N")
		)
	)
	(footprint ""
		(layer "F.Cu")
		(at 364.50143 -241.976656 -90)
		(property "Reference" "C1025"
			(at 0 0 270)
			(layer "F.SilkS")
			(hide yes)
			(effects
				(font
					(size 1.27 1.27)
				)
			)
		)
		(property "Value" ""
			(at 0 0 270)
			(layer "F.Fab")
			(effects
				(font
					(size 1.27 1.27)
				)
			)
		)
		(duplicate_pad_numbers_are_jumpers no)
		(fp_line
			(start -0.7874 0.4064)
			(end -0.7874 -0.4064)
			(stroke
				(width 0.1524)
				(type default)
			)
			(layer "F.SilkS")
		)
		(fp_line
			(start 0.7874 0.4064)
			(end -0.7874 0.4064)
			(stroke
				(width 0.1524)
				(type default)
			)
			(layer "F.SilkS")
		)
		(fp_line
			(start -0.7874 -0.4064)
			(end 0.7874 -0.4064)
			(stroke
				(width 0.1524)
				(type default)
			)
			(layer "F.SilkS")
		)
		(fp_line
			(start 0.7874 -0.4064)
			(end 0.7874 0.4064)
			(stroke
				(width 0.1524)
				(type default)
			)
			(layer "F.SilkS")
		)
		(fp_line
			(start -0.67945 0.3048)
			(end -0.67945 -0.305054)
			(stroke
				(width 0.1)
				(type default)
			)
			(layer "F.Fab")
		)
		(fp_line
			(start -0.12065 0.3048)
			(end -0.67945 0.3048)
			(stroke
				(width 0.1)
				(type default)
			)
			(layer "F.Fab")
		)
		(fp_line
			(start 0.120396 0.3048)
			(end 0.120396 0.2794)
			(stroke
				(width 0.1)
				(type default)
			)
			(layer "F.Fab")
		)
		(fp_line
			(start 0.67945 0.3048)
			(end 0.120396 0.3048)
			(stroke
				(width 0.1)
				(type default)
			)
			(layer "F.Fab")
		)
		(fp_line
			(start -0.12065 0.2794)
			(end -0.12065 0.3048)
			(stroke
				(width 0.1)
				(type default)
			)
			(layer "F.Fab")
		)
		(fp_line
			(start 0.120396 0.2794)
			(end -0.12065 0.2794)
			(stroke
				(width 0.1)
				(type default)
			)
			(layer "F.Fab")
		)
		(fp_line
			(start -0.12065 -0.2794)
			(end 0.12065 -0.2794)
			(stroke
				(width 0.1)
				(type default)
			)
			(layer "F.Fab")
		)
		(fp_line
			(start 0.12065 -0.2794)
			(end 0.12065 -0.3048)
			(stroke
				(width 0.1)
				(type default)
			)
			(layer "F.Fab")
		)
		(fp_line
			(start 0.12065 -0.3048)
			(end 0.67945 -0.3048)
			(stroke
				(width 0.1)
				(type default)
			)
			(layer "F.Fab")
		)
		(fp_line
			(start 0.67945 -0.3048)
			(end 0.67945 0.3048)
			(stroke
				(width 0.1)
				(type default)
			)
			(layer "F.Fab")
		)
		(fp_line
			(start -0.67945 -0.305054)
			(end -0.12065 -0.305054)
			(stroke
				(width 0.1)
				(type default)
			)
			(layer "F.Fab")
		)
		(fp_line
			(start -0.12065 -0.305054)
			(end -0.12065 -0.2794)
			(stroke
				(width 0.1)
				(type default)
			)
			(layer "F.Fab")
		)
		(pad "1" smd circle
			(at -0.40005 0 270)
			(size 0 0)
			(layers "F.Cu" "F.Mask" "F.Paste")
			(net "PVCCIN_CPU0")
		)
		(pad "2" smd circle
			(at 0.40005 0 270)
			(size 0 0)
			(layers "F.Cu" "F.Mask" "F.Paste")
			(net "GND")
		)
	)
)
